(kicad_pcb
	(version 20241229)
	(generator "pcbnew")
	(generator_version "9.0")
	(general
		(thickness 1.62)
		(legacy_teardrops no)
	)
	(paper "A3")
	(title_block
		(title "COM Express 7 Baseboard")
		(date "2025-02-04")
		(rev "1.1.2")
		(company "Antmicro Ltd")
		(comment 1 "www.antmicro.com")
		(comment 9 "footprint 489 of 802 (J12), pads 367-406 of 450")
	)
	(layers
		(0 "F.Cu" signal)
		(4 "In1.Cu" signal)
		(6 "In2.Cu" signal)
		(8 "In3.Cu" signal)
		(10 "In4.Cu" signal)
		(12 "In5.Cu" signal)
		(14 "In6.Cu" signal)
		(2 "B.Cu" signal)
		(9 "F.Adhes" user "F.Adhesive")
		(11 "B.Adhes" user "B.Adhesive")
		(13 "F.Paste" user)
		(15 "B.Paste" user)
		(5 "F.SilkS" user "F.Silkscreen")
		(7 "B.SilkS" user "B.Silkscreen")
		(1 "F.Mask" user)
		(3 "B.Mask" user)
		(17 "Dwgs.User" user "User.Drawings")
		(19 "Cmts.User" user "User.Comments")
		(21 "Eco1.User" user "User.Eco1")
		(23 "Eco2.User" user "User.Eco2")
		(25 "Edge.Cuts" user)
		(27 "Margin" user)
		(31 "F.CrtYd" user "F.Courtyard")
		(29 "B.CrtYd" user "B.Courtyard")
		(35 "F.Fab" user)
		(33 "B.Fab" user)
	)
	(footprint "antmicro-footprints:EPT_401-51501-51"
		(layer "F.Cu")
		(at 203.275 159.81)
		(property "Reference" "J12"
			(at 30.975 -10.45 0)
			(layer "F.SilkS")
			(effects
				(font
					(size 0.7 0.7)
					(thickness 0.15)
				)
				(justify right top)
			)
		)
		(property "Value" "Plug_Bus_CE7_EPT_401-51501-51"
			(at -3.225 52.665 0)
			(layer "F.Fab")
			(hide yes)
			(effects
				(font
					(size 0.7 0.7)
					(thickness 0.15)
				)
				(justify left top)
			)
		)
		(property "Datasheet" "https://www.farnell.com/datasheets/1905093.pdf"
			(at 0 0 0)
			(layer "F.Fab")
			(hide yes)
			(effects
				(font
					(size 1.27 1.27)
					(thickness 0.15)
				)
			)
		)
		(property "Author" "Antmicro"
			(at 406.55 319.62 0)
			(layer "F.Fab")
			(hide yes)
			(effects
				(font
					(size 1 1)
					(thickness 0.15)
				)
			)
		)
		(property "License" "Apache-2.0"
			(at 406.55 319.62 0)
			(layer "F.Fab")
			(hide yes)
			(effects
				(font
					(size 1 1)
					(thickness 0.15)
				)
			)
		)
		(property "MPN" "401-51501-51"
			(at 406.55 319.62 0)
			(layer "F.Fab")
			(hide yes)
			(effects
				(font
					(size 1 1)
					(thickness 0.15)
				)
			)
		)
		(property "Manufacturer" "ept"
			(at 406.55 319.62 0)
			(layer "F.Fab")
			(hide yes)
			(effects
				(font
					(size 1 1)
					(thickness 0.15)
				)
			)
		)
		(sheetname "Com Express 7 Interfaces")
		(sheetfile "com_express_7_interfaces.kicad_sch")
		(attr smd)
		(pad "D32" smd rect
			(at -11.75 -8.675)
			(size 0.3 1.75)
			(layers "F.Cu" "F.Mask" "F.Paste")
			(net 481 "unconnected-(J12K-10G_SFP_SCL3-PadD32)")
			(pinfunction "10G_SFP_SCL3")
			(pintype "open_collector+no_connect")
			(teardrops
				(best_length_ratio 0.2)
				(max_length 1)
				(best_width_ratio 0.9)
				(max_width 2)
				(curved_edges yes)
				(filter_ratio 0.9)
				(enabled yes)
				(allow_two_segments yes)
				(prefer_zone_connections yes)
			)
		)
		(pad "D33" smd rect
			(at -11.25 -8.675)
			(size 0.3 1.75)
			(layers "F.Cu" "F.Mask" "F.Paste")
			(net 482 "unconnected-(J12K-10G_SFP_SCL2-PadD33)")
			(pinfunction "10G_SFP_SCL2")
			(pintype "open_collector+no_connect")
			(teardrops
				(best_length_ratio 0.2)
				(max_length 1)
				(best_width_ratio 0.9)
				(max_width 2)
				(curved_edges yes)
				(filter_ratio 0.9)
				(enabled yes)
				(allow_two_segments yes)
				(prefer_zone_connections yes)
			)
		)
		(pad "D34" smd rect
			(at -10.75 -8.675)
			(size 0.3 1.75)
			(layers "F.Cu" "F.Mask" "F.Paste")
			(net 483 "unconnected-(J12K-10G_PHY_CAP_23-PadD34)")
			(pinfunction "10G_PHY_CAP_23")
			(pintype "input+no_connect")
			(teardrops
				(best_length_ratio 0.2)
				(max_length 1)
				(best_width_ratio 0.9)
				(max_width 2)
				(curved_edges yes)
				(filter_ratio 0.9)
				(enabled yes)
				(allow_two_segments yes)
				(prefer_zone_connections yes)
			)
		)
		(pad "D35" smd rect
			(at -10.25 -8.675)
			(size 0.3 1.75)
			(layers "F.Cu" "F.Mask" "F.Paste")
			(net 484 "Net-(J12K-10G_PHY_CAP_01)")
			(pinfunction "10G_PHY_CAP_01")
			(pintype "input")
			(teardrops
				(best_length_ratio 0.2)
				(max_length 1)
				(best_width_ratio 0.9)
				(max_width 2)
				(curved_edges yes)
				(filter_ratio 0.9)
				(enabled yes)
				(allow_two_segments yes)
				(prefer_zone_connections yes)
			)
		)
		(pad "D36" smd rect
			(at -9.75 -8.675)
			(size 0.3 1.75)
			(layers "F.Cu" "F.Mask" "F.Paste")
			(net 485 "unconnected-(J12M-RSVD-PadD36)")
			(pinfunction "RSVD")
			(pintype "no_connect")
			(teardrops
				(best_length_ratio 0.2)
				(max_length 1)
				(best_width_ratio 0.9)
				(max_width 2)
				(curved_edges yes)
				(filter_ratio 0.9)
				(enabled yes)
				(allow_two_segments yes)
				(prefer_zone_connections yes)
			)
		)
		(pad "D37" smd rect
			(at -9.25 -8.675)
			(size 0.3 1.75)
			(layers "F.Cu" "F.Mask" "F.Paste")
			(net 486 "unconnected-(J12M-RSVD-PadD37)")
			(pinfunction "RSVD")
			(pintype "no_connect")
			(teardrops
				(best_length_ratio 0.2)
				(max_length 1)
				(best_width_ratio 0.9)
				(max_width 2)
				(curved_edges yes)
				(filter_ratio 0.9)
				(enabled yes)
				(allow_two_segments yes)
				(prefer_zone_connections yes)
			)
		)
		(pad "D38" smd rect
			(at -8.75 -8.675)
			(size 0.3 1.75)
			(layers "F.Cu" "F.Mask" "F.Paste")
			(net 487 "/2xSFP+/I2C_{SFP1}.SCL")
			(pinfunction "10G_SFP_SCL1")
			(pintype "open_collector")
			(teardrops
				(best_length_ratio 0.2)
				(max_length 1)
				(best_width_ratio 0.9)
				(max_width 2)
				(curved_edges yes)
				(filter_ratio 0.9)
				(enabled yes)
				(allow_two_segments yes)
				(prefer_zone_connections yes)
			)
		)
		(pad "D39" smd rect
			(at -8.25 -8.675)
			(size 0.3 1.75)
			(layers "F.Cu" "F.Mask" "F.Paste")
			(net 488 "/2xSFP+/I2C_{SFP0}.SCL")
			(pinfunction "10G_SFP_SCL0")
			(pintype "open_collector")
			(teardrops
				(best_length_ratio 0.2)
				(max_length 1)
				(best_width_ratio 0.9)
				(max_width 2)
				(curved_edges yes)
				(filter_ratio 0.9)
				(enabled yes)
				(allow_two_segments yes)
				(prefer_zone_connections yes)
			)
		)
		(pad "D40" smd rect
			(at -7.75 -8.675)
			(size 0.3 1.75)
			(layers "F.Cu" "F.Mask" "F.Paste")
			(net 489 "Net-(J12K-10G_SDP1)")
			(pinfunction "10G_SDP1")
			(pintype "bidirectional")
			(teardrops
				(best_length_ratio 0.2)
				(max_length 1)
				(best_width_ratio 0.9)
				(max_width 2)
				(curved_edges yes)
				(filter_ratio 0.9)
				(enabled yes)
				(allow_two_segments yes)
				(prefer_zone_connections yes)
			)
		)
		(pad "D41" smd rect
			(at -7.25 -8.675)
			(size 0.3 1.75)
			(layers "F.Cu" "F.Mask" "F.Paste")
			(net 1 "GND")
			(pinfunction "GND(FIXED)")
			(pintype "passive")
			(teardrops
				(best_length_ratio 0.2)
				(max_length 1)
				(best_width_ratio 0.9)
				(max_width 2)
				(curved_edges yes)
				(filter_ratio 0.9)
				(enabled yes)
				(allow_two_segments yes)
				(prefer_zone_connections yes)
			)
		)
		(pad "D42" smd rect
			(at -6.75 -8.675)
			(size 0.3 1.75)
			(layers "F.Cu" "F.Mask" "F.Paste")
			(net 119 "/2xSFP+/10GKR_SFP1.TX+")
			(pinfunction "10G_KR_TX1+")
			(pintype "output")
			(teardrops
				(best_length_ratio 0.2)
				(max_length 1)
				(best_width_ratio 0.9)
				(max_width 2)
				(curved_edges yes)
				(filter_ratio 0.9)
				(enabled yes)
				(allow_two_segments yes)
				(prefer_zone_connections yes)
			)
		)
		(pad "D43" smd rect
			(at -6.25 -8.675)
			(size 0.3 1.75)
			(layers "F.Cu" "F.Mask" "F.Paste")
			(net 121 "/2xSFP+/10GKR_SFP1.TX-")
			(pinfunction "10G_KR_TX1-")
			(pintype "output")
			(teardrops
				(best_length_ratio 0.2)
				(max_length 1)
				(best_width_ratio 0.9)
				(max_width 2)
				(curved_edges yes)
				(filter_ratio 0.9)
				(enabled yes)
				(allow_two_segments yes)
				(prefer_zone_connections yes)
			)
		)
		(pad "D44" smd rect
			(at -5.75 -8.675)
			(size 0.3 1.75)
			(layers "F.Cu" "F.Mask" "F.Paste")
			(net 1 "GND")
			(pinfunction "GND")
			(pintype "passive")
			(teardrops
				(best_length_ratio 0.2)
				(max_length 1)
				(best_width_ratio 0.9)
				(max_width 2)
				(curved_edges yes)
				(filter_ratio 0.9)
				(enabled yes)
				(allow_two_segments yes)
				(prefer_zone_connections yes)
			)
		)
		(pad "D45" smd rect
			(at -5.25 -8.675)
			(size 0.3 1.75)
			(layers "F.Cu" "F.Mask" "F.Paste")
			(net 490 "/2xSFP+/MDIO1.MDIO")
			(pinfunction "10G_PHY_MDIO_SDA1")
			(pintype "open_collector")
			(teardrops
				(best_length_ratio 0.2)
				(max_length 1)
				(best_width_ratio 0.9)
				(max_width 2)
				(curved_edges yes)
				(filter_ratio 0.9)
				(enabled yes)
				(allow_two_segments yes)
				(prefer_zone_connections yes)
			)
		)
		(pad "D46" smd rect
			(at -4.75 -8.675)
			(size 0.3 1.75)
			(layers "F.Cu" "F.Mask" "F.Paste")
			(net 491 "/2xSFP+/MDIO0.MDIO")
			(pinfunction "10G_PHY_MDIO_SDA0")
			(pintype "open_collector")
			(teardrops
				(best_length_ratio 0.2)
				(max_length 1)
				(best_width_ratio 0.9)
				(max_width 2)
				(curved_edges yes)
				(filter_ratio 0.9)
				(enabled yes)
				(allow_two_segments yes)
				(prefer_zone_connections yes)
			)
		)
		(pad "D47" smd rect
			(at -4.25 -8.675)
			(size 0.3 1.75)
			(layers "F.Cu" "F.Mask" "F.Paste")
			(net 492 "/2xSFP+/MOD1_ABS")
			(pinfunction "10G_INT1")
			(pintype "input")
			(teardrops
				(best_length_ratio 0.2)
				(max_length 1)
				(best_width_ratio 0.9)
				(max_width 2)
				(curved_edges yes)
				(filter_ratio 0.9)
				(enabled yes)
				(allow_two_segments yes)
				(prefer_zone_connections yes)
			)
		)
		(pad "D48" smd rect
			(at -3.75 -8.675)
			(size 0.3 1.75)
			(layers "F.Cu" "F.Mask" "F.Paste")
			(net 1 "GND")
			(pinfunction "GND")
			(pintype "passive")
			(teardrops
				(best_length_ratio 0.2)
				(max_length 1)
				(best_width_ratio 0.9)
				(max_width 2)
				(curved_edges yes)
				(filter_ratio 0.9)
				(enabled yes)
				(allow_two_segments yes)
				(prefer_zone_connections yes)
			)
		)
		(pad "D49" smd rect
			(at -3.25 -8.675)
			(size 0.3 1.75)
			(layers "F.Cu" "F.Mask" "F.Paste")
			(net 111 "/2xSFP+/10GKR_SFP0.TX+")
			(pinfunction "10G_KR_TX0+")
			(pintype "output")
			(teardrops
				(best_length_ratio 0.2)
				(max_length 1)
				(best_width_ratio 0.9)
				(max_width 2)
				(curved_edges yes)
				(filter_ratio 0.9)
				(enabled yes)
				(allow_two_segments yes)
				(prefer_zone_connections yes)
			)
		)
		(pad "D50" smd rect
			(at -2.75 -8.675)
			(size 0.3 1.75)
			(layers "F.Cu" "F.Mask" "F.Paste")
			(net 113 "/2xSFP+/10GKR_SFP0.TX-")
			(pinfunction "10G_KR_TX0-")
			(pintype "output")
			(teardrops
				(best_length_ratio 0.2)
				(max_length 1)
				(best_width_ratio 0.9)
				(max_width 2)
				(curved_edges yes)
				(filter_ratio 0.9)
				(enabled yes)
				(allow_two_segments yes)
				(prefer_zone_connections yes)
			)
		)
		(pad "D51" smd rect
			(at -2.25 -8.675)
			(size 0.3 1.75)
			(layers "F.Cu" "F.Mask" "F.Paste")
			(net 1 "GND")
			(pinfunction "GND(FIXED)")
			(pintype "passive")
			(teardrops
				(best_length_ratio 0.2)
				(max_length 1)
				(best_width_ratio 0.9)
				(max_width 2)
				(curved_edges yes)
				(filter_ratio 0.9)
				(enabled yes)
				(allow_two_segments yes)
				(prefer_zone_connections yes)
			)
		)
		(pad "D52" smd rect
			(at -1.75 -8.675)
			(size 0.3 1.75)
			(layers "F.Cu" "F.Mask" "F.Paste")
			(net 866 "/Backplane/PCIe_{x2}.TX0+")
			(pinfunction "PCIE_TX16+")
			(pintype "output")
			(teardrops
				(best_length_ratio 0.2)
				(max_length 1)
				(best_width_ratio 0.9)
				(max_width 2)
				(curved_edges yes)
				(filter_ratio 0.9)
				(enabled yes)
				(allow_two_segments yes)
				(prefer_zone_connections yes)
			)
		)
		(pad "D53" smd rect
			(at -1.25 -8.675)
			(size 0.3 1.75)
			(layers "F.Cu" "F.Mask" "F.Paste")
			(net 867 "/Backplane/PCIe_{x2}.TX0-")
			(pinfunction "PCIE_TX16-")
			(pintype "output")
			(teardrops
				(best_length_ratio 0.2)
				(max_length 1)
				(best_width_ratio 0.9)
				(max_width 2)
				(curved_edges yes)
				(filter_ratio 0.9)
				(enabled yes)
				(allow_two_segments yes)
				(prefer_zone_connections yes)
			)
		)
		(pad "D54" smd rect
			(at -0.75 -8.675)
			(size 0.3 1.75)
			(layers "F.Cu" "F.Mask" "F.Paste")
			(net 493 "unconnected-(J12M-RSVD-PadD54)")
			(pinfunction "RSVD")
			(pintype "no_connect")
			(teardrops
				(best_length_ratio 0.2)
				(max_length 1)
				(best_width_ratio 0.9)
				(max_width 2)
				(curved_edges yes)
				(filter_ratio 0.9)
				(enabled yes)
				(allow_two_segments yes)
				(prefer_zone_connections yes)
			)
		)
		(pad "D55" smd rect
			(at -0.25 -8.675)
			(size 0.3 1.75)
			(layers "F.Cu" "F.Mask" "F.Paste")
			(net 868 "/Backplane/PCIe_{x2}.TX1+")
			(pinfunction "PCIE_TX17+")
			(pintype "output")
			(teardrops
				(best_length_ratio 0.2)
				(max_length 1)
				(best_width_ratio 0.9)
				(max_width 2)
				(curved_edges yes)
				(filter_ratio 0.9)
				(enabled yes)
				(allow_two_segments yes)
				(prefer_zone_connections yes)
			)
		)
		(pad "D56" smd rect
			(at 0.25 -8.675)
			(size 0.3 1.75)
			(layers "F.Cu" "F.Mask" "F.Paste")
			(net 869 "/Backplane/PCIe_{x2}.TX1-")
			(pinfunction "PCIE_TX17-")
			(pintype "output")
			(teardrops
				(best_length_ratio 0.2)
				(max_length 1)
				(best_width_ratio 0.9)
				(max_width 2)
				(curved_edges yes)
				(filter_ratio 0.9)
				(enabled yes)
				(allow_two_segments yes)
				(prefer_zone_connections yes)
			)
		)
		(pad "D57" smd rect
			(at 0.75 -8.675)
			(size 0.3 1.75)
			(layers "F.Cu" "F.Mask" "F.Paste")
			(net 137 "/Com Express 7 MGMT/~{TYPE2}")
			(pinfunction "~{TYPE2}")
			(pintype "passive")
			(teardrops
				(best_length_ratio 0.2)
				(max_length 1)
				(best_width_ratio 0.9)
				(max_width 2)
				(curved_edges yes)
				(filter_ratio 0.9)
				(enabled yes)
				(allow_two_segments yes)
				(prefer_zone_connections yes)
			)
		)
		(pad "D58" smd rect
			(at 1.25 -8.675)
			(size 0.3 1.75)
			(layers "F.Cu" "F.Mask" "F.Paste")
			(net 885 "unconnected-(J12N-PCIE_TX18+-PadD58)")
			(pinfunction "PCIE_TX18+")
			(pintype "output+no_connect")
			(teardrops
				(best_length_ratio 0.2)
				(max_length 1)
				(best_width_ratio 0.9)
				(max_width 2)
				(curved_edges yes)
				(filter_ratio 0.9)
				(enabled yes)
				(allow_two_segments yes)
				(prefer_zone_connections yes)
			)
		)
		(pad "D59" smd rect
			(at 1.75 -8.675)
			(size 0.3 1.75)
			(layers "F.Cu" "F.Mask" "F.Paste")
			(net 886 "unconnected-(J12N-PCIE_TX18--PadD59)")
			(pinfunction "PCIE_TX18-")
			(pintype "output+no_connect")
			(teardrops
				(best_length_ratio 0.2)
				(max_length 1)
				(best_width_ratio 0.9)
				(max_width 2)
				(curved_edges yes)
				(filter_ratio 0.9)
				(enabled yes)
				(allow_two_segments yes)
				(prefer_zone_connections yes)
			)
		)
		(pad "D60" smd rect
			(at 2.25 -8.675)
			(size 0.3 1.75)
			(layers "F.Cu" "F.Mask" "F.Paste")
			(net 1 "GND")
			(pinfunction "GND(FIXED)")
			(pintype "passive")
			(teardrops
				(best_length_ratio 0.2)
				(max_length 1)
				(best_width_ratio 0.9)
				(max_width 2)
				(curved_edges yes)
				(filter_ratio 0.9)
				(enabled yes)
				(allow_two_segments yes)
				(prefer_zone_connections yes)
			)
		)
		(pad "D61" smd rect
			(at 2.75 -8.675)
			(size 0.3 1.75)
			(layers "F.Cu" "F.Mask" "F.Paste")
			(net 887 "unconnected-(J12N-PCIE_TX19+-PadD61)")
			(pinfunction "PCIE_TX19+")
			(pintype "output+no_connect")
			(teardrops
				(best_length_ratio 0.2)
				(max_length 1)
				(best_width_ratio 0.9)
				(max_width 2)
				(curved_edges yes)
				(filter_ratio 0.9)
				(enabled yes)
				(allow_two_segments yes)
				(prefer_zone_connections yes)
			)
		)
		(pad "D62" smd rect
			(at 3.25 -8.675)
			(size 0.3 1.75)
			(layers "F.Cu" "F.Mask" "F.Paste")
			(net 888 "unconnected-(J12N-PCIE_TX19--PadD62)")
			(pinfunction "PCIE_TX19-")
			(pintype "output+no_connect")
			(teardrops
				(best_length_ratio 0.2)
				(max_length 1)
				(best_width_ratio 0.9)
				(max_width 2)
				(curved_edges yes)
				(filter_ratio 0.9)
				(enabled yes)
				(allow_two_segments yes)
				(prefer_zone_connections yes)
			)
		)
		(pad "D63" smd rect
			(at 3.75 -8.675)
			(size 0.3 1.75)
			(layers "F.Cu" "F.Mask" "F.Paste")
			(net 494 "unconnected-(J12M-RSVD-PadD63)")
			(pinfunction "RSVD")
			(pintype "no_connect")
			(teardrops
				(best_length_ratio 0.2)
				(max_length 1)
				(best_width_ratio 0.9)
				(max_width 2)
				(curved_edges yes)
				(filter_ratio 0.9)
				(enabled yes)
				(allow_two_segments yes)
				(prefer_zone_connections yes)
			)
		)
		(pad "D64" smd rect
			(at 4.25 -8.675)
			(size 0.3 1.75)
			(layers "F.Cu" "F.Mask" "F.Paste")
			(net 495 "unconnected-(J12M-RSVD-PadD64)")
			(pinfunction "RSVD")
			(pintype "no_connect")
			(teardrops
				(best_length_ratio 0.2)
				(max_length 1)
				(best_width_ratio 0.9)
				(max_width 2)
				(curved_edges yes)
				(filter_ratio 0.9)
				(enabled yes)
				(allow_two_segments yes)
				(prefer_zone_connections yes)
			)
		)
		(pad "D65" smd rect
			(at 4.75 -8.675)
			(size 0.3 1.75)
			(layers "F.Cu" "F.Mask" "F.Paste")
			(net 496 "unconnected-(J12N-PCIE_TX20+-PadD65)")
			(pinfunction "PCIE_TX20+")
			(pintype "output+no_connect")
			(teardrops
				(best_length_ratio 0.2)
				(max_length 1)
				(best_width_ratio 0.9)
				(max_width 2)
				(curved_edges yes)
				(filter_ratio 0.9)
				(enabled yes)
				(allow_two_segments yes)
				(prefer_zone_connections yes)
			)
		)
		(pad "D66" smd rect
			(at 5.25 -8.675)
			(size 0.3 1.75)
			(layers "F.Cu" "F.Mask" "F.Paste")
			(net 497 "unconnected-(J12N-PCIE_TX20--PadD66)")
			(pinfunction "PCIE_TX20-")
			(pintype "output+no_connect")
			(teardrops
				(best_length_ratio 0.2)
				(max_length 1)
				(best_width_ratio 0.9)
				(max_width 2)
				(curved_edges yes)
				(filter_ratio 0.9)
				(enabled yes)
				(allow_two_segments yes)
				(prefer_zone_connections yes)
			)
		)
		(pad "D67" smd rect
			(at 5.75 -8.675)
			(size 0.3 1.75)
			(layers "F.Cu" "F.Mask" "F.Paste")
			(net 1 "GND")
			(pinfunction "GND")
			(pintype "passive")
			(teardrops
				(best_length_ratio 0.2)
				(max_length 1)
				(best_width_ratio 0.9)
				(max_width 2)
				(curved_edges yes)
				(filter_ratio 0.9)
				(enabled yes)
				(allow_two_segments yes)
				(prefer_zone_connections yes)
			)
		)
		(pad "D68" smd rect
			(at 6.25 -8.675)
			(size 0.3 1.75)
			(layers "F.Cu" "F.Mask" "F.Paste")
			(net 498 "unconnected-(J12N-PCIE_TX21+-PadD68)")
			(pinfunction "PCIE_TX21+")
			(pintype "output+no_connect")
			(teardrops
				(best_length_ratio 0.2)
				(max_length 1)
				(best_width_ratio 0.9)
				(max_width 2)
				(curved_edges yes)
				(filter_ratio 0.9)
				(enabled yes)
				(allow_two_segments yes)
				(prefer_zone_connections yes)
			)
		)
		(pad "D69" smd rect
			(at 6.75 -8.675)
			(size 0.3 1.75)
			(layers "F.Cu" "F.Mask" "F.Paste")
			(net 499 "unconnected-(J12N-PCIE_TX21--PadD69)")
			(pinfunction "PCIE_TX21-")
			(pintype "output+no_connect")
			(teardrops
				(best_length_ratio 0.2)
				(max_length 1)
				(best_width_ratio 0.9)
				(max_width 2)
				(curved_edges yes)
				(filter_ratio 0.9)
				(enabled yes)
				(allow_two_segments yes)
				(prefer_zone_connections yes)
			)
		)
		(pad "D70" smd rect
			(at 7.25 -8.675)
			(size 0.3 1.75)
			(layers "F.Cu" "F.Mask" "F.Paste")
			(net 1 "GND")
			(pinfunction "GND(FIXED)")
			(pintype "passive")
			(teardrops
				(best_length_ratio 0.2)
				(max_length 1)
				(best_width_ratio 0.9)
				(max_width 2)
				(curved_edges yes)
				(filter_ratio 0.9)
				(enabled yes)
				(allow_two_segments yes)
				(prefer_zone_connections yes)
			)
		)
		(pad "D71" smd rect
			(at 7.75 -8.675)
			(size 0.3 1.75)
			(layers "F.Cu" "F.Mask" "F.Paste")
			(net 500 "unconnected-(J12N-PCIE_TX22+-PadD71)")
			(pinfunction "PCIE_TX22+")
			(pintype "output+no_connect")
			(teardrops
				(best_length_ratio 0.2)
				(max_length 1)
				(best_width_ratio 0.9)
				(max_width 2)
				(curved_edges yes)
				(filter_ratio 0.9)
				(enabled yes)
				(allow_two_segments yes)
				(prefer_zone_connections yes)
			)
		)
	)
)
